# S9S_MB_2U (Grand Teton) — schematic netlist excerpt (pin names and nets, part order shuffled) for the footprints in the layout excerpt that follows; sources: Cadence DE-HDL packaged netlist, KiCad conversion of 03242023_DA0F0TMBIJ0_F0T_Motherboard_J_brd_V01_OCP.brd

R4521  Q_RES  10K 1% CHIP  pkg 0402LF  page 212 : A = P3V3_AUX ; B = CLK_GEN2_BMC_RC_OE_N
C396  Q_CAP  47UF 4V 20% X6S  pkg C0805  page 76 : A = PVCCIN_CPU0 ; B = GND
R690  Q_RES  33.2 1% CHIP  pkg 0402LF  page 229 : A = I3C_SPD_DDREFGH_CPU0_SDA ; B = I3C_SPD_DDREFGH_CPU0_R_SDA

(kicad_pcb
	(version 20260206)
	(generator "pcbnew")
	(generator_version "10.0")
	(general
		(thickness 1.6)
		(legacy_teardrops no)
	)
	(paper "A4")
	(title_block
		(title "03242023_DA0F0TMBIJ0_F0T_Motherboard_J_brd_V01_OCP.brd")
		(comment 1 "Grand Teton / footprints 5836-5838 of 6105")
	)
	(layers
		(0 "F.Cu" signal "TOP")
		(4 "In1.Cu" signal "GND")
		(6 "In2.Cu" signal "IN1")
		(8 "In3.Cu" signal "GND1")
		(10 "In4.Cu" signal "IN2")
		(12 "In5.Cu" signal "GND2")
		(14 "In6.Cu" signal "IN3")
		(16 "In7.Cu" signal "GND3")
		(18 "In8.Cu" signal "VCC")
		(20 "In9.Cu" signal "VCC1")
		(22 "In10.Cu" signal "GND4")
		(24 "In11.Cu" signal "IN4")
		(26 "In12.Cu" signal "GND5")
		(28 "In13.Cu" signal "IN5")
		(30 "In14.Cu" signal "GND6")
		(32 "In15.Cu" signal "IN6")
		(34 "In16.Cu" signal "GND7")
		(2 "B.Cu" signal "BOTTOM")
		(9 "F.Adhes" user "F.Adhesive")
		(11 "B.Adhes" user "B.Adhesive")
		(13 "F.Paste" user "Package Geometry/Pastemask Top")
		(15 "B.Paste" user "Package Geometry/Pastemask Bottom")
		(5 "F.SilkS" user "Ref Des/Silkscreen Top")
		(7 "B.SilkS" user "Ref Des/Silkscreen Bottom")
		(1 "F.Mask" user "Board Geometry/Soldermask Top")
		(3 "B.Mask" user "Board Geometry/Soldermask Bottom")
		(17 "Dwgs.User" user "User.Drawings")
		(19 "Cmts.User" user "User.Comments")
		(21 "Eco1.User" user "User.Eco1")
		(23 "Eco2.User" user "User.Eco2")
		(25 "Edge.Cuts" user "Board Geometry/Outline")
		(27 "Margin" user)
		(31 "F.CrtYd" user "Package Geometry/Place Bound Top")
		(29 "B.CrtYd" user "Package Geometry/Place Bound Bottom")
		(35 "F.Fab" user "Ref Des/Assembly Top")
		(33 "B.Fab" user "Ref Des/Assembly Bottom")
	)
	(footprint ""
		(layer "B.Cu")
		(at 379.720602 -190.795148 90)
		(property "Reference" "R690"
			(at 0 0 90)
			(layer "B.SilkS")
			(hide yes)
			(effects
				(font
					(size 1.27 1.27)
				)
				(justify mirror)
			)
		)
		(property "Value" ""
			(at 0 0 90)
			(layer "B.Fab")
			(effects
				(font
					(size 1.27 1.27)
				)
				(justify mirror)
			)
		)
		(duplicate_pad_numbers_are_jumpers no)
		(fp_line
			(start 0.7874 -0.4064)
			(end -0.7874 -0.4064)
			(stroke
				(width 0.1524)
				(type default)
			)
			(layer "B.SilkS")
		)
		(fp_line
			(start -0.7874 -0.4064)
			(end -0.7874 0.4064)
			(stroke
				(width 0.1524)
				(type default)
			)
			(layer "B.SilkS")
		)
		(fp_line
			(start 0.7874 0.4064)
			(end 0.7874 -0.4064)
			(stroke
				(width 0.1524)
				(type default)
			)
			(layer "B.SilkS")
		)
		(fp_line
			(start -0.7874 0.4064)
			(end 0.7874 0.4064)
			(stroke
				(width 0.1524)
				(type default)
			)
			(layer "B.SilkS")
		)
		(fp_line
			(start 0.67945 -0.305054)
			(end 0.12065 -0.305054)
			(stroke
				(width 0.1)
				(type default)
			)
			(layer "B.Fab")
		)
		(fp_line
			(start 0.12065 -0.305054)
			(end 0.12065 -0.2794)
			(stroke
				(width 0.1)
				(type default)
			)
			(layer "B.Fab")
		)
		(fp_line
			(start -0.12065 -0.3048)
			(end -0.67945 -0.3048)
			(stroke
				(width 0.1)
				(type default)
			)
			(layer "B.Fab")
		)
		(fp_line
			(start -0.67945 -0.3048)
			(end -0.67945 0.3048)
			(stroke
				(width 0.1)
				(type default)
			)
			(layer "B.Fab")
		)
		(fp_line
			(start 0.12065 -0.2794)
			(end -0.12065 -0.2794)
			(stroke
				(width 0.1)
				(type default)
			)
			(layer "B.Fab")
		)
		(fp_line
			(start -0.12065 -0.2794)
			(end -0.12065 -0.3048)
			(stroke
				(width 0.1)
				(type default)
			)
			(layer "B.Fab")
		)
		(fp_line
			(start 0.12065 0.2794)
			(end 0.12065 0.3048)
			(stroke
				(width 0.1)
				(type default)
			)
			(layer "B.Fab")
		)
		(fp_line
			(start -0.120396 0.2794)
			(end 0.12065 0.2794)
			(stroke
				(width 0.1)
				(type default)
			)
			(layer "B.Fab")
		)
		(fp_line
			(start 0.67945 0.3048)
			(end 0.67945 -0.305054)
			(stroke
				(width 0.1)
				(type default)
			)
			(layer "B.Fab")
		)
		(fp_line
			(start 0.12065 0.3048)
			(end 0.67945 0.3048)
			(stroke
				(width 0.1)
				(type default)
			)
			(layer "B.Fab")
		)
		(fp_line
			(start -0.120396 0.3048)
			(end -0.120396 0.2794)
			(stroke
				(width 0.1)
				(type default)
			)
			(layer "B.Fab")
		)
		(fp_line
			(start -0.67945 0.3048)
			(end -0.120396 0.3048)
			(stroke
				(width 0.1)
				(type default)
			)
			(layer "B.Fab")
		)
		(pad "1" smd circle
			(at 0.40005 0 270)
			(size 0 0)
			(layers "B.Cu" "B.Mask" "B.Paste")
			(net "I3C_SPD_DDREFGH_CPU0_SDA")
		)
		(pad "2" smd circle
			(at -0.40005 0 270)
			(size 0 0)
			(layers "B.Cu" "B.Mask" "B.Paste")
			(net "I3C_SPD_DDREFGH_CPU0_R_SDA")
		)
	)
	(footprint ""
		(layer "B.Cu")
		(at 197.182232 -123.139708 180)
		(property "Reference" "R4521"
			(at 0 0 0)
			(layer "B.SilkS")
			(hide yes)
			(effects
				(font
					(size 1.27 1.27)
				)
				(justify mirror)
			)
		)
		(property "Value" ""
			(at 0 0 0)
			(layer "B.Fab")
			(effects
				(font
					(size 1.27 1.27)
				)
				(justify mirror)
			)
		)
		(duplicate_pad_numbers_are_jumpers no)
		(fp_line
			(start 0.7874 0.4064)
			(end 0.7874 -0.4064)
			(stroke
				(width 0.1524)
				(type default)
			)
			(layer "B.SilkS")
		)
		(fp_line
			(start 0.7874 -0.4064)
			(end -0.7874 -0.4064)
			(stroke
				(width 0.1524)
				(type default)
			)
			(layer "B.SilkS")
		)
		(fp_line
			(start -0.7874 0.4064)
			(end 0.7874 0.4064)
			(stroke
				(width 0.1524)
				(type default)
			)
			(layer "B.SilkS")
		)
		(fp_line
			(start -0.7874 -0.4064)
			(end -0.7874 0.4064)
			(stroke
				(width 0.1524)
				(type default)
			)
			(layer "B.SilkS")
		)
		(fp_line
			(start 0.67945 0.3048)
			(end 0.67945 -0.305054)
			(stroke
				(width 0.1)
				(type default)
			)
			(layer "B.Fab")
		)
		(fp_line
			(start 0.67945 -0.305054)
			(end 0.12065 -0.305054)
			(stroke
				(width 0.1)
				(type default)
			)
			(layer "B.Fab")
		)
		(fp_line
			(start 0.12065 0.3048)
			(end 0.67945 0.3048)
			(stroke
				(width 0.1)
				(type default)
			)
			(layer "B.Fab")
		)
		(fp_line
			(start 0.12065 0.2794)
			(end 0.12065 0.3048)
			(stroke
				(width 0.1)
				(type default)
			)
			(layer "B.Fab")
		)
		(fp_line
			(start 0.12065 -0.2794)
			(end -0.12065 -0.2794)
			(stroke
				(width 0.1)
				(type default)
			)
			(layer "B.Fab")
		)
		(fp_line
			(start 0.12065 -0.305054)
			(end 0.12065 -0.2794)
			(stroke
				(width 0.1)
				(type default)
			)
			(layer "B.Fab")
		)
		(fp_line
			(start -0.120396 0.3048)
			(end -0.120396 0.2794)
			(stroke
				(width 0.1)
				(type default)
			)
			(layer "B.Fab")
		)
		(fp_line
			(start -0.120396 0.2794)
			(end 0.12065 0.2794)
			(stroke
				(width 0.1)
				(type default)
			)
			(layer "B.Fab")
		)
		(fp_line
			(start -0.12065 -0.2794)
			(end -0.12065 -0.3048)
			(stroke
				(width 0.1)
				(type default)
			)
			(layer "B.Fab")
		)
		(fp_line
			(start -0.12065 -0.3048)
			(end -0.67945 -0.3048)
			(stroke
				(width 0.1)
				(type default)
			)
			(layer "B.Fab")
		)
		(fp_line
			(start -0.67945 0.3048)
			(end -0.120396 0.3048)
			(stroke
				(width 0.1)
				(type default)
			)
			(layer "B.Fab")
		)
		(fp_line
			(start -0.67945 -0.3048)
			(end -0.67945 0.3048)
			(stroke
				(width 0.1)
				(type default)
			)
			(layer "B.Fab")
		)
		(pad "1" smd circle
			(at 0.40005 0)
			(size 0 0)
			(layers "B.Cu" "B.Mask" "B.Paste")
			(net "P3V3_AUX")
		)
		(pad "2" smd circle
			(at -0.40005 0)
			(size 0 0)
			(layers "B.Cu" "B.Mask" "B.Paste")
			(net "CLK_GEN2_BMC_RC_OE_N")
		)
	)
	(footprint ""
		(layer "B.Cu")
		(at 366.310418 -296.054526)
		(property "Reference" "C396"
			(at 0 0 0)
			(layer "B.SilkS")
			(hide yes)
			(effects
				(font
					(size 1.27 1.27)
				)
				(justify mirror)
			)
		)
		(property "Value" ""
			(at 0 0 0)
			(layer "B.Fab")
			(effects
				(font
					(size 1.27 1.27)
				)
				(justify mirror)
			)
		)
		(duplicate_pad_numbers_are_jumpers no)
		(fp_line
			(start -1.524 -0.762)
			(end -1.524 0.762)
			(stroke
				(width 0.1524)
				(type default)
			)
			(layer "B.SilkS")
		)
		(fp_line
			(start -1.524 0.762)
			(end 1.524 0.762)
			(stroke
				(width 0.1524)
				(type default)
			)
			(layer "B.SilkS")
		)
		(fp_line
			(start 1.524 -0.762)
			(end -1.524 -0.762)
			(stroke
				(width 0.1524)
				(type default)
			)
			(layer "B.SilkS")
		)
		(fp_line
			(start 1.524 0.762)
			(end 1.524 -0.762)
			(stroke
				(width 0.1524)
				(type default)
			)
			(layer "B.SilkS")
		)
		(fp_line
			(start -1.1049 -0.724916)
			(end 1.1049 -0.724916)
			(stroke
				(width 0.1)
				(type default)
			)
			(layer "B.Fab")
		)
		(fp_line
			(start -1.1049 0.724916)
			(end -1.1049 -0.724916)
			(stroke
				(width 0.1)
				(type default)
			)
			(layer "B.Fab")
		)
		(fp_line
			(start 1.1049 -0.724916)
			(end 1.1049 0.724916)
			(stroke
				(width 0.1)
				(type default)
			)
			(layer "B.Fab")
		)
		(fp_line
			(start 1.1049 0.724916)
			(end -1.1049 0.724916)
			(stroke
				(width 0.1)
				(type default)
			)
			(layer "B.Fab")
		)
		(pad "1" smd rect
			(at 0.889 0)
			(size 1.016 1.27)
			(layers "B.Cu" "B.Mask" "B.Paste")
			(net "PVCCIN_CPU0")
		)
		(pad "2" smd rect
			(at -0.889 0)
			(size 1.016 1.27)
			(layers "B.Cu" "B.Mask" "B.Paste")
			(net "GND")
		)
	)
)
